# BASEBOARD_FAB2 (Tioga Pass) — schematic netlist excerpt (pin names and nets, part order shuffled) for the footprints in the layout excerpt that follows; sources: Cadence DE-HDL packaged netlist, KiCad conversion of Wiwynn_Tioga_Pass_MB.brd

J6B1  SCONN120_H61426002  CONN  pkg SM  page 194
  IOA1  = P12V_STBY
  IOA2  = P12V_STBY
  IOA3  = P12V_STBY
  IOA4  = P12V_STBY
  IOA5  = P12V_STBY
  IOA6  = P12V_STBY
  IOA7  = P12V_STBY
  IOA8  = P12V_STBY
  IOA9  = GND
  IOA10  = GND
  IOA11  = P3V3_STBY
  IOA12  = GND
  IOA13  = P5V_STBY
  IOA14  = GND
  IOA15  = FM_P1V8MCP_CPU0_EN
  IOA16  = FM_PVCCIOMCP_CPU0_EN
  IOA17  = GND
  IOA18  = SMB_VR_STBY_LVC3_SCL
  IOA19  = SVID_ALERT0_CPU0_R_N
  IOA20  = SVID_CLK0_CPU0_R
  IOB1  = P12V_STBY
  IOB2  = P12V_STBY
  IOB3  = P12V_STBY
  IOB4  = P12V_STBY
  IOB5  = P12V_STBY
  IOB6  = P12V_STBY
  IOB7  = P12V_STBY
  IOB8  = P12V_STBY
  IOB9  = GND
  IOB10  = GND
  IOB11  = P3V3_STBY
  IOB12  = GND
  IOB13  = P5V_STBY
  IOB14  = GND
  IOB15  = PWRGD_P1V8MCP_CPU0
  IOB16  = PWRGD_PVCCIOMCP_CPU0
  IOB17  = GND
  IOB18  = SMB_VR_STBY_LVC3_SDA
  IOB19  = SVID_ALERT1_CPU0_R_N
  IOB20  = SVID_DIO0_CPU0_R
  IOC1  = GND
  IOC2  = GND
  IOC3  = GND
  IOC4  = GND
  IOC5  = GND
  IOC6  = GND
  IOC7  = GND
  IOC8  = GND
  IOC9  = GND
  IOC10  = GND
  IOC11  = P3V3_STBY
  IOC12  = GND
  IOC13  = P5V_STBY
  IOC14  = GND
  IOC15  = GND
  IOC16  = GND
  IOC17  = PVCCIOMCP_CPU0
  IOC18  = PVCCIOMCP_CPU0
  IOC19  = PVCCIOMCP_CPU0
  IOC20  = FM_PVCCMCP_CPU0_EN
  IOD1  = P3V3
  IOD2  = GND
  IOD3  = GND
  IOD4  = GND
  IOD5  = GND
  IOD6  = GND
  IOD7  = GND
  IOD8  = GND
  IOD9  = GND
  IOD10  = GND
  IOD11  = GND
  IOD12  = GND
  IOD13  = GND
  IOD14  = GND
  IOD15  = GND
  IOD16  = GND
  IOD17  = PVCCIOMCP_CPU0
  IOD18  = PVCCIOMCP_CPU0
  IOD19  = PVCCIOMCP_CPU0
  IOD20  = PWRGD_PVCCMCP_CPU0
  IOE1  = FM_CPU0_VRM_322M_156M_OSC_EN
  IOE2  = GND
  IOE3  = GND
  IOE4  = GND
  IOE5  = GND
  IOE6  = GND
  IOE7  = GND
  IOE8  = VSENSE_PVCCIOMCP_CPU0_SKT_VSEN
  IOE9  = GND
  IOE10  = VR_PVCCIOMCP_CPU0_XADDR1
  IOE11  = GND
  IOE12  = GND
  IOE13  = GND
  IOE14  = GND
  IOE15  = PVCCIOMCP_CPU0
  IOE16  = PVCCIOMCP_CPU0
  IOE17  = PVCCIOMCP_CPU0
  IOE18  = PVCCIOMCP_CPU0
  IOE19  = PVCCIOMCP_CPU0
  IOE20  = SVID_CLK1_CPU0_R
  IOF1  = PVCCIO_CPU0
  IOF2  = GND
  IOF3  = GND
  IOF4  = GND
  IOF5  = GND
  IOF6  = GND
  IOF7  = GND
  IOF8  = VSENSE_PVCCIOMCP_CPU0_SKT_VRTN
  IOF9  = GND
  IOF10  = VR_PVCCMCP_CPU0_XADDR2
  IOF11  = GND
  IOF12  = GND
  IOF13  = GND
  IOF14  = GND
  IOF15  = PVCCIOMCP_CPU0
  IOF16  = PVCCIOMCP_CPU0
  IOF17  = PVCCIOMCP_CPU0
  IOF18  = PVCCIOMCP_CPU0
  IOF19  = PVCCIOMCP_CPU0
  IOF20  = SVID_DIO1_CPU0_R

(kicad_pcb
	(version 20260206)
	(generator "pcbnew")
	(generator_version "10.0")
	(general
		(thickness 1.6)
		(legacy_teardrops no)
	)
	(paper "A4")
	(title_block
		(title "Wiwynn_Tioga_Pass_MB.brd")
		(comment 1 "Tioga Pass / footprint 1366 of 4770 (J6B1), pads 103-122 of 122")
	)
	(layers
		(0 "F.Cu" signal "TOP")
		(4 "In1.Cu" signal "L2GND")
		(6 "In2.Cu" signal "L3")
		(8 "In3.Cu" signal "L4GND")
		(10 "In4.Cu" signal "L5")
		(12 "In5.Cu" signal "L6GND")
		(14 "In6.Cu" signal "L7VCC")
		(16 "In7.Cu" signal "L8VCC")
		(18 "In8.Cu" signal "L9GND")
		(20 "In9.Cu" signal "L10")
		(22 "In10.Cu" signal "L11GND")
		(24 "In11.Cu" signal "L12")
		(26 "In12.Cu" signal "L13GND")
		(2 "B.Cu" signal "BOTTOM")
		(9 "F.Adhes" user "F.Adhesive")
		(11 "B.Adhes" user "B.Adhesive")
		(13 "F.Paste" user "Package Geometry/Pastemask Top")
		(15 "B.Paste" user "Package Geometry/Pastemask Bottom")
		(5 "F.SilkS" user "Ref Des/Silkscreen Top")
		(7 "B.SilkS" user "Ref Des/Silkscreen Bottom")
		(1 "F.Mask" user "Board Geometry/Soldermask Top")
		(3 "B.Mask" user "Board Geometry/Soldermask Bottom")
		(17 "Dwgs.User" user "User.Drawings")
		(19 "Cmts.User" user "User.Comments")
		(21 "Eco1.User" user "User.Eco1")
		(23 "Eco2.User" user "User.Eco2")
		(25 "Edge.Cuts" user "Board Geometry/Outline")
		(27 "Margin" user)
		(31 "F.CrtYd" user "Package Geometry/Place Bound Top")
		(29 "B.CrtYd" user "Package Geometry/Place Bound Bottom")
		(35 "F.Fab" user "Ref Des/Assembly Top")
		(33 "B.Fab" user "Ref Des/Assembly Bottom")
	)
	(footprint ""
		(layer "F.Cu")
		(at 329.594972 -115.55095 90)
		(property "Reference" "J6B1"
			(at -3.59283 -5.018024 90)
			(unlocked yes)
			(layer "F.SilkS")
			(effects
				(font
					(size 0.7874 0.5842)
					(thickness 0.1524)
				)
			)
		)
		(property "Value" ""
			(at 0 0 90)
			(layer "F.Fab")
			(effects
				(font
					(size 1.27 1.27)
				)
			)
		)
		(duplicate_pad_numbers_are_jumpers no)
		(pad "F1" smd circle
			(at -6.35 0 90)
			(size 0.635 0.635)
			(layers "F.Cu" "F.Mask" "F.Paste")
			(net "PVCCIO_CPU0")
		)
		(pad "F2" smd circle
			(at -6.35 1.27 90)
			(size 0.635 0.635)
			(layers "F.Cu" "F.Mask" "F.Paste")
			(net "GND")
		)
		(pad "F3" smd circle
			(at -6.35 2.54 90)
			(size 0.635 0.635)
			(layers "F.Cu" "F.Mask" "F.Paste")
			(net "GND")
		)
		(pad "F4" smd circle
			(at -6.35 3.81 90)
			(size 0.635 0.635)
			(layers "F.Cu" "F.Mask" "F.Paste")
			(net "GND")
		)
		(pad "F5" smd circle
			(at -6.35 5.08 90)
			(size 0.635 0.635)
			(layers "F.Cu" "F.Mask" "F.Paste")
			(net "GND")
		)
		(pad "F6" smd circle
			(at -6.35 6.35 90)
			(size 0.635 0.635)
			(layers "F.Cu" "F.Mask" "F.Paste")
			(net "GND")
		)
		(pad "F7" smd circle
			(at -6.35 7.62 90)
			(size 0.635 0.635)
			(layers "F.Cu" "F.Mask" "F.Paste")
			(net "GND")
		)
		(pad "F8" smd circle
			(at -6.35 8.89 90)
			(size 0.635 0.635)
			(layers "F.Cu" "F.Mask" "F.Paste")
			(net "VSENSE_PVCCIOMCP_CPU0_SKT_VRTN")
		)
		(pad "F9" smd circle
			(at -6.35 10.16 90)
			(size 0.635 0.635)
			(layers "F.Cu" "F.Mask" "F.Paste")
			(net "GND")
		)
		(pad "F10" smd circle
			(at -6.35 11.43 90)
			(size 0.635 0.635)
			(layers "F.Cu" "F.Mask" "F.Paste")
			(net "VR_PVCCMCP_CPU0_XADDR2")
		)
		(pad "F11" smd circle
			(at -6.35 12.7 90)
			(size 0.635 0.635)
			(layers "F.Cu" "F.Mask" "F.Paste")
			(net "GND")
		)
		(pad "F12" smd circle
			(at -6.35 13.97 90)
			(size 0.635 0.635)
			(layers "F.Cu" "F.Mask" "F.Paste")
			(net "GND")
		)
		(pad "F13" smd circle
			(at -6.35 15.24 90)
			(size 0.635 0.635)
			(layers "F.Cu" "F.Mask" "F.Paste")
			(net "GND")
		)
		(pad "F14" smd circle
			(at -6.35 16.51 90)
			(size 0.635 0.635)
			(layers "F.Cu" "F.Mask" "F.Paste")
			(net "GND")
		)
		(pad "F15" smd circle
			(at -6.35 17.78 90)
			(size 0.635 0.635)
			(layers "F.Cu" "F.Mask" "F.Paste")
			(net "PVCCIOMCP_CPU0")
		)
		(pad "F16" smd circle
			(at -6.35 19.05 90)
			(size 0.635 0.635)
			(layers "F.Cu" "F.Mask" "F.Paste")
			(net "PVCCIOMCP_CPU0")
		)
		(pad "F17" smd circle
			(at -6.35 20.32 90)
			(size 0.635 0.635)
			(layers "F.Cu" "F.Mask" "F.Paste")
			(net "PVCCIOMCP_CPU0")
		)
		(pad "F18" smd circle
			(at -6.35 21.59 90)
			(size 0.635 0.635)
			(layers "F.Cu" "F.Mask" "F.Paste")
			(net "PVCCIOMCP_CPU0")
		)
		(pad "F19" smd circle
			(at -6.35 22.86 90)
			(size 0.635 0.635)
			(layers "F.Cu" "F.Mask" "F.Paste")
			(net "PVCCIOMCP_CPU0")
		)
		(pad "F20" smd circle
			(at -6.35 24.13 90)
			(size 0.635 0.635)
			(layers "F.Cu" "F.Mask" "F.Paste")
			(net "SVID_DIO1_CPU0_R")
		)
	)
)
